FILE_TYPE = MACRO_DRAWING;
SET COLOR_WIRE YELLOW;
SET COLOR_PROP ORANGE;
SET COLOR_DOT WHITE;
SET COLOR_ARC YELLOW;
SET COLOR_BODY GREEN;
SET COLOR_NOTE PURPLE;
SET PROP_DISPLAY VALUE;
SET PAGE_NUMBER P147;
FORCEADD QUANTA_TITLE_BLOCK_C..1
(0 0);
FORCEPROP 1 LAST CUSTOM_TXT_CDS <NAME_2>
J 0
(-3175 50);
FORCEPROP 1 LAST CUSTOM_TXT_CDS <NAME_1>
J 0
(-3175 175);
FORCEPROP 1 LAST CUSTOM_TXT_CDS <Q_NUMBER>
J 0
(-1403 103);
DISPLAY 1.212766 (-1403 103);
FORCEPROP 1 LAST CUSTOM_TXT_CDS <Q_PROJ>
J 0
(-2382 102);
DISPLAY 1.212766 (-2382 102);
FORCEPROP 1 LAST CUSTOM_TXT_CDS <Q_REV>
J 0
(-184 103);
DISPLAY 1.212766 (-184 103);
FORCEPROP 1 LAST CUSTOM_TXT_CDS <CON_LAST_MODIFIED>
J 0
(-1885 15);
DISPLAY 0.978723 (-1885 15);
FORCEPROP 1 LAST CUSTOM_TXT_CDS <CON_PAGE_NUM> OF <CON_TOTAL_PAGES>
J 0
(-446 18);
DISPLAY 0.978723 (-446 18);
FORCEPROP 1 LAST Q_TITLE Blank
J 0
(-9275 100);
DISPLAY 2.446809 (-9275 100);
PAINT GREEN (-9275 100);
FORCEPROP 2 LAST PAGE_BORDER TRUE
J 0
(-7890 5250);
DISPLAY 0.638298 (-7890 5250);
PAINT PINK (-7890 5250);
DISPLAY INVISIBLE (-7890 5250);
FORCEPROP 1 LAST CDS_LMAN_SYM_OUTLINE -9475,6775,100,-125
J 0
(0 0);
DISPLAY 0.468085 (0 0);
PAINT GREEN (0 0);
DISPLAY INVISIBLE (0 0);
FORCEPROP 2 LAST CDS_LIB pure_quanta
J 0
(0 0);
DISPLAY INVISIBLE (0 0);
FORCEPROP 2 LAST CDS_XR_PAGE_TITLE CR-170 : @T6G_MB_LIB.T6G(SCH_1):PAGE170
J 0
(-7890 5250);
DISPLAY 0.638298 (-7890 5250);
PAINT PINK (-7890 5250);
DISPLAY INVISIBLE (-7890 5250);
FORCEPROP 2 LAST CUSTOM_TXT_CDS <XR_PAGE_TITLE>
J 0
(-7890 5250);
DISPLAY 0.638298 (-7890 5250);
PAINT PINK (-7890 5250);
DISPLAY INVISIBLE (-7890 5250);
FORCEPROP 1 LAST COMMENT_BODY TRUE
J 0
(12 -13);
DISPLAY 0.978723 (12 -13);
PAINT GREEN (12 -13);
DISPLAY INVISIBLE (12 -13);
FORCEPROP 1 LAST Q_DEPT BU9
J 1
(-3763 49);
DISPLAY 1.957447 (-3763 49);
PAINT GREEN (-3763 49);
DISPLAY INVISIBLE (-3763 49);
FORCEPROP 0 LAST CDS_CON_LAST_MODIFIED Thu Aug 24 10:14:51 2023
J 0
(-1885 15);
DISPLAY INVISIBLE (-1885 15);
QUIT
